(kicad_pcb
	(version 20260206)
	(generator "pcbnew")
	(generator_version "10.0")
	(general
		(thickness 1.6)
		(legacy_teardrops no)
	)
	(paper "A4")
	(title_block
		(title "Bryce Canyon_IOM_IOC_16318-2_OCP.brd")
		(comment 1 "Bryce Canyon / footprints 781-788 of 1605")
	)
	(layers
		(0 "F.Cu" signal "TOP")
		(4 "In1.Cu" signal "L2GND")
		(6 "In2.Cu" signal "L3")
		(8 "In3.Cu" signal "L4VCC")
		(10 "In4.Cu" signal "L5VCC")
		(12 "In5.Cu" signal "L6")
		(14 "In6.Cu" signal "L7GND")
		(2 "B.Cu" signal "BOTTOM")
		(9 "F.Adhes" user "F.Adhesive")
		(11 "B.Adhes" user "B.Adhesive")
		(13 "F.Paste" user "Package Geometry/Pastemask Top")
		(15 "B.Paste" user "Package Geometry/Pastemask Bottom")
		(5 "F.SilkS" user "Ref Des/Silkscreen Top")
		(7 "B.SilkS" user "Ref Des/Silkscreen Bottom")
		(1 "F.Mask" user "Board Geometry/Soldermask Top")
		(3 "B.Mask" user "Board Geometry/Soldermask Bottom")
		(17 "Dwgs.User" user "User.Drawings")
		(19 "Cmts.User" user "User.Comments")
		(21 "Eco1.User" user "User.Eco1")
		(23 "Eco2.User" user "User.Eco2")
		(25 "Edge.Cuts" user "Board Geometry/Outline")
		(27 "Margin" user)
		(31 "F.CrtYd" user "Package Geometry/Place Bound Top")
		(29 "B.CrtYd" user "Package Geometry/Place Bound Bottom")
		(35 "F.Fab" user "Ref Des/Assembly Top")
		(33 "B.Fab" user "Ref Des/Assembly Bottom")
	)
	(footprint ""
		(layer "F.Cu")
		(at 66.71183 -179.375054 180)
		(property "Reference" "R82"
			(at 0 0 180)
			(layer "F.SilkS")
			(hide yes)
			(effects
				(font
					(size 1.27 1.27)
				)
			)
		)
		(property "Value" "10KR2F-2-GP"
			(at 0.064008 -3.99415 180)
			(unlocked yes)
			(layer "F.Fab")
			(hide yes)
			(effects
				(font
					(size 1.016 1.016)
					(thickness 0.1524)
				)
			)
		)
		(property "Device Type" "R402H16"
			(at 0.064262 -5.51815 180)
			(unlocked yes)
			(layer "F.Fab")
			(hide yes)
			(effects
				(font
					(size 1.016 1.016)
					(thickness 0.1524)
				)
			)
		)
		(duplicate_pad_numbers_are_jumpers no)
		(fp_line
			(start 0.508 -0.9398)
			(end -0.508 -0.9398)
			(stroke
				(width 0.1524)
				(type default)
			)
			(layer "F.SilkS")
		)
		(fp_line
			(start -0.508 -0.9398)
			(end -0.508 0.9398)
			(stroke
				(width 0.1524)
				(type default)
			)
			(layer "F.SilkS")
		)
		(fp_rect
			(start -0.508 0.9398)
			(end 0.508 -0.9398)
			(stroke
				(width 0)
				(type default)
			)
			(fill no)
			(layer "F.CrtYd")
		)
		(fp_rect
			(start -0.508 0.9398)
			(end 0.508 -0.9398)
			(stroke
				(width 0)
				(type default)
			)
			(fill no)
			(layer "F.Fab")
		)
		(pad "1" smd custom
			(at 0 -0.4445 180)
			(size 0.1397 0.1397)
			(layers "F.Cu" "F.Mask" "F.Paste")
			(net "VREF_2V2")
			(options
				(clearance outline)
				(anchor circle)
			)
			(primitives
				(gr_poly
					(pts
						(arc
							(start -0.1778 -0.2794)
							(mid -0.249642 -0.249642)
							(end -0.2794 -0.1778)
						)
						(arc
							(start -0.2794 0.1778)
							(mid -0.249642 0.249642)
							(end -0.1778 0.2794)
						)
						(arc
							(start 0.1778 0.2794)
							(mid 0.249642 0.249642)
							(end 0.2794 0.1778)
						)
						(arc
							(start 0.2794 -0.1778)
							(mid 0.249642 -0.249642)
							(end 0.1778 -0.2794)
						)
					)
					(width 0)
					(fill yes)
				)
			)
		)
		(pad "2" smd custom
			(at 0 0.4445 180)
			(size 0.1397 0.1397)
			(layers "F.Cu" "F.Mask" "F.Paste")
			(net "GND")
			(options
				(clearance outline)
				(anchor circle)
			)
			(primitives
				(gr_poly
					(pts
						(arc
							(start -0.1778 -0.2794)
							(mid -0.249642 -0.249642)
							(end -0.2794 -0.1778)
						)
						(arc
							(start -0.2794 0.1778)
							(mid -0.249642 0.249642)
							(end -0.1778 0.2794)
						)
						(arc
							(start 0.1778 0.2794)
							(mid 0.249642 0.249642)
							(end 0.2794 0.1778)
						)
						(arc
							(start 0.2794 -0.1778)
							(mid 0.249642 -0.249642)
							(end 0.1778 -0.2794)
						)
					)
					(width 0)
					(fill yes)
				)
			)
		)
	)
	(footprint ""
		(layer "F.Cu")
		(at 172.942504 -138.259566 -90)
		(property "Reference" "C152"
			(at 0 0 270)
			(layer "F.SilkS")
			(hide yes)
			(effects
				(font
					(size 1.27 1.27)
				)
			)
		)
		(property "Value" "SC10U16V5KX-7-GP-U"
			(at -0.0762 -6.1214 270)
			(unlocked yes)
			(layer "F.Fab")
			(hide yes)
			(effects
				(font
					(size 1.016 1.016)
					(thickness 0.1524)
				)
			)
		)
		(property "Device Type" "C805H58"
			(at -0.0762 -8.1534 270)
			(unlocked yes)
			(layer "F.Fab")
			(hide yes)
			(effects
				(font
					(size 1.016 1.016)
					(thickness 0.1524)
				)
			)
		)
		(duplicate_pad_numbers_are_jumpers no)
		(fp_line
			(start 0.635 0)
			(end -0.635 0)
			(stroke
				(width 0.508)
				(type default)
			)
			(layer "F.SilkS")
		)
		(fp_rect
			(start -0.9652 1.778)
			(end 0.9652 -1.778)
			(stroke
				(width 0)
				(type default)
			)
			(fill no)
			(layer "F.CrtYd")
		)
		(fp_poly
			(pts
				(xy -0.9652 -1.778) (xy 0.9652 -1.778) (xy 0.9652 1.778) (xy -0.9652 1.778)
			)
			(stroke
				(width 0)
				(type default)
			)
			(fill no)
			(layer "F.Fab")
		)
		(pad "1" smd rect
			(at 0 -0.9652 270)
			(size 1.397 1.143)
			(layers "F.Cu" "F.Mask" "F.Paste")
			(net "P12V_STBY_VIN_PU1")
		)
		(pad "2" smd rect
			(at 0 0.9652 270)
			(size 1.397 1.143)
			(layers "F.Cu" "F.Mask" "F.Paste")
			(net "GND")
		)
	)
	(footprint ""
		(layer "F.Cu")
		(at 83.358228 -82.149696 90)
		(property "Reference" "VIA12"
			(at 0 0 90)
			(layer "F.SilkS")
			(hide yes)
			(effects
				(font
					(size 1.27 1.27)
				)
			)
		)
		(property "Value" "85OHM-8L-1D6MM-L16L18-GP"
			(at 4.064 0.6096 90)
			(unlocked yes)
			(layer "F.Fab")
			(hide yes)
			(effects
				(font
					(size 1.016 1.016)
					(thickness 0.1524)
				)
			)
		)
		(property "Device Type" "VIA-PCIE-4P-368076"
			(at 4.064 -0.9144 90)
			(unlocked yes)
			(layer "F.Fab")
			(hide yes)
			(effects
				(font
					(size 1.016 1.016)
					(thickness 0.1524)
				)
			)
		)
		(duplicate_pad_numbers_are_jumpers no)
		(fp_rect
			(start -1.8415 0.381)
			(end 1.8415 -0.381)
			(stroke
				(width 0)
				(type default)
			)
			(fill no)
			(layer "F.CrtYd")
		)
		(fp_rect
			(start -1.8415 0.381)
			(end 1.8415 -0.381)
			(stroke
				(width 0)
				(type default)
			)
			(fill no)
			(layer "F.Fab")
		)
		(pad "1" thru_hole circle
			(at -1.4605 0 90)
			(size 0.508 0.508)
			(drill 0.254)
			(layers "*.Cu" "*.Mask")
			(remove_unused_layers no)
			(net "GND")
			(clearance 0.127)
			(thermal_gap 0.127)
		)
		(pad "2" thru_hole circle
			(at -0.4445 0 90)
			(size 0.508 0.508)
			(drill 0.254)
			(layers "*.Cu" "*.Mask")
			(remove_unused_layers no)
			(net "PCIE_IOM_TO_COMP_19_DP")
			(clearance 0.127)
			(thermal_gap 0.127)
		)
		(pad "3" thru_hole circle
			(at 0.4445 0 90)
			(size 0.508 0.508)
			(drill 0.254)
			(layers "*.Cu" "*.Mask")
			(remove_unused_layers no)
			(net "PCIE_IOM_TO_COMP_19_DN")
			(clearance 0.127)
			(thermal_gap 0.127)
		)
		(pad "4" thru_hole circle
			(at 1.4605 0 90)
			(size 0.508 0.508)
			(drill 0.254)
			(layers "*.Cu" "*.Mask")
			(remove_unused_layers no)
			(net "GND")
			(clearance 0.127)
			(thermal_gap 0.127)
		)
	)
	(footprint ""
		(layer "F.Cu")
		(at 173.863 -77.978 90)
		(property "Reference" "R619"
			(at 0 0 90)
			(layer "F.SilkS")
			(hide yes)
			(effects
				(font
					(size 1.27 1.27)
				)
			)
		)
		(property "Value" "4K7R2F-GP"
			(at 0.064008 -3.993896 90)
			(unlocked yes)
			(layer "F.Fab")
			(hide yes)
			(effects
				(font
					(size 1.016 1.016)
					(thickness 0.1524)
				)
			)
		)
		(property "Device Type" "R402H16"
			(at 0.064008 -5.517896 90)
			(unlocked yes)
			(layer "F.Fab")
			(hide yes)
			(effects
				(font
					(size 1.016 1.016)
					(thickness 0.1524)
				)
			)
		)
		(duplicate_pad_numbers_are_jumpers no)
		(fp_line
			(start 0.508 -0.9398)
			(end -0.508 -0.9398)
			(stroke
				(width 0.1524)
				(type default)
			)
			(layer "F.SilkS")
		)
		(fp_line
			(start -0.508 -0.9398)
			(end -0.508 0.9398)
			(stroke
				(width 0.1524)
				(type default)
			)
			(layer "F.SilkS")
		)
		(fp_rect
			(start -0.508 0.9398)
			(end 0.508 -0.9398)
			(stroke
				(width 0)
				(type default)
			)
			(fill no)
			(layer "F.CrtYd")
		)
		(fp_rect
			(start -0.508 0.9398)
			(end 0.508 -0.9398)
			(stroke
				(width 0)
				(type default)
			)
			(fill no)
			(layer "F.Fab")
		)
		(pad "1" smd custom
			(at 0 -0.4445 90)
			(size 0.1397 0.1397)
			(layers "F.Cu" "F.Mask" "F.Paste")
			(net "P1V8")
			(options
				(clearance outline)
				(anchor circle)
			)
			(primitives
				(gr_poly
					(pts
						(arc
							(start -0.1778 -0.2794)
							(mid -0.249642 -0.249642)
							(end -0.2794 -0.1778)
						)
						(arc
							(start -0.2794 0.1778)
							(mid -0.249642 0.249642)
							(end -0.1778 0.2794)
						)
						(arc
							(start 0.1778 0.2794)
							(mid 0.249642 0.249642)
							(end 0.2794 0.1778)
						)
						(arc
							(start 0.2794 -0.1778)
							(mid 0.249642 -0.249642)
							(end 0.1778 -0.2794)
						)
					)
					(width 0)
					(fill yes)
				)
			)
		)
		(pad "2" smd custom
			(at 0 0.4445 90)
			(size 0.1397 0.1397)
			(layers "F.Cu" "F.Mask" "F.Paste")
			(net "UART_SERCLK")
			(options
				(clearance outline)
				(anchor circle)
			)
			(primitives
				(gr_poly
					(pts
						(arc
							(start -0.1778 -0.2794)
							(mid -0.249642 -0.249642)
							(end -0.2794 -0.1778)
						)
						(arc
							(start -0.2794 0.1778)
							(mid -0.249642 0.249642)
							(end -0.1778 0.2794)
						)
						(arc
							(start 0.1778 0.2794)
							(mid 0.249642 0.249642)
							(end 0.2794 0.1778)
						)
						(arc
							(start 0.2794 -0.1778)
							(mid 0.249642 -0.249642)
							(end 0.1778 -0.2794)
						)
					)
					(width 0)
					(fill yes)
				)
			)
		)
	)
	(footprint ""
		(layer "F.Cu")
		(at 37.3126 -175.6664 -90)
		(property "Reference" "C183"
			(at 0 0 270)
			(layer "F.SilkS")
			(hide yes)
			(effects
				(font
					(size 1.27 1.27)
				)
			)
		)
		(property "Value" "SC1KP50V2KX-1GP"
			(at 1.1811 -2.7051 270)
			(unlocked yes)
			(layer "F.Fab")
			(hide yes)
			(effects
				(font
					(size 1.016 1.016)
					(thickness 0.1524)
				)
			)
		)
		(property "Device Type" "C402H22"
			(at 1.1811 -4.2291 270)
			(unlocked yes)
			(layer "F.Fab")
			(hide yes)
			(effects
				(font
					(size 1.016 1.016)
					(thickness 0.1524)
				)
			)
		)
		(duplicate_pad_numbers_are_jumpers no)
		(fp_rect
			(start -0.4318 0.9525)
			(end 0.4318 -0.9525)
			(stroke
				(width 0)
				(type default)
			)
			(fill no)
			(layer "F.CrtYd")
		)
		(fp_rect
			(start -0.4318 0.9525)
			(end 0.4318 -0.9525)
			(stroke
				(width 0)
				(type default)
			)
			(fill no)
			(layer "F.Fab")
		)
		(pad "1" smd custom
			(at 0 -0.4445 270)
			(size 0.1524 0.1524)
			(layers "F.Cu" "F.Mask" "F.Paste")
			(net "P3V3_STBY_LL_R")
			(options
				(clearance outline)
				(anchor circle)
			)
			(primitives
				(gr_poly
					(pts
						(arc
							(start 0.3048 -0.2032)
							(mid 0.275042 -0.275042)
							(end 0.2032 -0.3048)
						)
						(arc
							(start -0.2032 -0.3048)
							(mid -0.275042 -0.275042)
							(end -0.3048 -0.2032)
						)
						(arc
							(start -0.3048 0.2032)
							(mid -0.275042 0.275042)
							(end -0.2032 0.3048)
						)
						(arc
							(start 0.2032 0.3048)
							(mid 0.275042 0.275042)
							(end 0.3048 0.2032)
						)
					)
					(width 0)
					(fill yes)
				)
			)
		)
		(pad "2" smd custom
			(at 0 0.4445 270)
			(size 0.1524 0.1524)
			(layers "F.Cu" "F.Mask" "F.Paste")
			(net "P3V3_STBY_VFB")
			(options
				(clearance outline)
				(anchor circle)
			)
			(primitives
				(gr_poly
					(pts
						(arc
							(start 0.3048 -0.2032)
							(mid 0.275042 -0.275042)
							(end 0.2032 -0.3048)
						)
						(arc
							(start -0.2032 -0.3048)
							(mid -0.275042 -0.275042)
							(end -0.3048 -0.2032)
						)
						(arc
							(start -0.3048 0.2032)
							(mid -0.275042 0.275042)
							(end -0.2032 0.3048)
						)
						(arc
							(start 0.2032 0.3048)
							(mid 0.275042 0.275042)
							(end 0.3048 0.2032)
						)
					)
					(width 0)
					(fill yes)
				)
			)
		)
	)
	(footprint ""
		(layer "F.Cu")
		(at 224.934272 -81.366614)
		(property "Reference" "R622"
			(at 0 0 0)
			(layer "F.SilkS")
			(hide yes)
			(effects
				(font
					(size 1.27 1.27)
				)
			)
		)
		(property "Value" "150R2F-1-GP"
			(at 0.064008 -3.993896 0)
			(unlocked yes)
			(layer "F.Fab")
			(hide yes)
			(effects
				(font
					(size 1.016 1.016)
					(thickness 0.1524)
				)
			)
		)
		(property "Device Type" "R402H16"
			(at 0.064008 -5.517896 0)
			(unlocked yes)
			(layer "F.Fab")
			(hide yes)
			(effects
				(font
					(size 1.016 1.016)
					(thickness 0.1524)
				)
			)
		)
		(duplicate_pad_numbers_are_jumpers no)
		(fp_line
			(start -0.508 -0.9398)
			(end -0.508 0.9398)
			(stroke
				(width 0.1524)
				(type default)
			)
			(layer "F.SilkS")
		)
		(fp_line
			(start 0.508 -0.9398)
			(end -0.508 -0.9398)
			(stroke
				(width 0.1524)
				(type default)
			)
			(layer "F.SilkS")
		)
		(fp_rect
			(start -0.508 0.9398)
			(end 0.508 -0.9398)
			(stroke
				(width 0)
				(type default)
			)
			(fill no)
			(layer "F.CrtYd")
		)
		(fp_rect
			(start -0.508 0.9398)
			(end 0.508 -0.9398)
			(stroke
				(width 0)
				(type default)
			)
			(fill no)
			(layer "F.Fab")
		)
		(pad "1" smd custom
			(at 0 -0.4445)
			(size 0.1397 0.1397)
			(layers "F.Cu" "F.Mask" "F.Paste")
			(net "P3V3")
			(options
				(clearance outline)
				(anchor circle)
			)
			(primitives
				(gr_poly
					(pts
						(arc
							(start -0.1778 -0.2794)
							(mid -0.249642 -0.249642)
							(end -0.2794 -0.1778)
						)
						(arc
							(start -0.2794 0.1778)
							(mid -0.249642 0.249642)
							(end -0.1778 0.2794)
						)
						(arc
							(start 0.1778 0.2794)
							(mid 0.249642 0.249642)
							(end 0.2794 0.1778)
						)
						(arc
							(start 0.2794 -0.1778)
							(mid 0.249642 -0.249642)
							(end 0.1778 -0.2794)
						)
					)
					(width 0)
					(fill yes)
				)
			)
		)
		(pad "2" smd custom
			(at 0 0.4445)
			(size 0.1397 0.1397)
			(layers "F.Cu" "F.Mask" "F.Paste")
			(net "SYS_ERROR_LED_R")
			(options
				(clearance outline)
				(anchor circle)
			)
			(primitives
				(gr_poly
					(pts
						(arc
							(start -0.1778 -0.2794)
							(mid -0.249642 -0.249642)
							(end -0.2794 -0.1778)
						)
						(arc
							(start -0.2794 0.1778)
							(mid -0.249642 0.249642)
							(end -0.1778 0.2794)
						)
						(arc
							(start 0.1778 0.2794)
							(mid 0.249642 0.249642)
							(end 0.2794 0.1778)
						)
						(arc
							(start 0.2794 -0.1778)
							(mid 0.249642 -0.249642)
							(end 0.1778 -0.2794)
						)
					)
					(width 0)
					(fill yes)
				)
			)
		)
	)
	(footprint ""
		(layer "F.Cu")
		(at 62.015624 -156.333698)
		(property "Reference" "R335"
			(at 0 0 0)
			(layer "F.SilkS")
			(hide yes)
			(effects
				(font
					(size 1.27 1.27)
				)
			)
		)
		(property "Value" "0R2J-2-GP"
			(at 0.064008 -3.993896 0)
			(unlocked yes)
			(layer "F.Fab")
			(hide yes)
			(effects
				(font
					(size 1.016 1.016)
					(thickness 0.1524)
				)
			)
		)
		(property "Device Type" "R402H16"
			(at 0.064008 -5.517896 0)
			(unlocked yes)
			(layer "F.Fab")
			(hide yes)
			(effects
				(font
					(size 1.016 1.016)
					(thickness 0.1524)
				)
			)
		)
		(duplicate_pad_numbers_are_jumpers no)
		(fp_line
			(start -0.508 -0.9398)
			(end -0.508 0.9398)
			(stroke
				(width 0.1524)
				(type default)
			)
			(layer "F.SilkS")
		)
		(fp_line
			(start 0.508 -0.9398)
			(end -0.508 -0.9398)
			(stroke
				(width 0.1524)
				(type default)
			)
			(layer "F.SilkS")
		)
		(fp_rect
			(start -0.508 0.9398)
			(end 0.508 -0.9398)
			(stroke
				(width 0)
				(type default)
			)
			(fill no)
			(layer "F.CrtYd")
		)
		(fp_rect
			(start -0.508 0.9398)
			(end 0.508 -0.9398)
			(stroke
				(width 0)
				(type default)
			)
			(fill no)
			(layer "F.Fab")
		)
		(pad "1" smd custom
			(at 0 -0.4445)
			(size 0.1397 0.1397)
			(layers "F.Cu" "F.Mask" "F.Paste")
			(net "NCSI_TXD1")
			(options
				(clearance outline)
				(anchor circle)
			)
			(primitives
				(gr_poly
					(pts
						(arc
							(start -0.1778 -0.2794)
							(mid -0.249642 -0.249642)
							(end -0.2794 -0.1778)
						)
						(arc
							(start -0.2794 0.1778)
							(mid -0.249642 0.249642)
							(end -0.1778 0.2794)
						)
						(arc
							(start 0.1778 0.2794)
							(mid 0.249642 0.249642)
							(end 0.2794 0.1778)
						)
						(arc
							(start 0.2794 -0.1778)
							(mid 0.249642 -0.249642)
							(end 0.1778 -0.2794)
						)
					)
					(width 0)
					(fill yes)
				)
			)
		)
		(pad "2" smd custom
			(at 0 0.4445)
			(size 0.1397 0.1397)
			(layers "F.Cu" "F.Mask" "F.Paste")
			(net "NCSI_TXD1_R")
			(options
				(clearance outline)
				(anchor circle)
			)
			(primitives
				(gr_poly
					(pts
						(arc
							(start -0.1778 -0.2794)
							(mid -0.249642 -0.249642)
							(end -0.2794 -0.1778)
						)
						(arc
							(start -0.2794 0.1778)
							(mid -0.249642 0.249642)
							(end -0.1778 0.2794)
						)
						(arc
							(start 0.1778 0.2794)
							(mid 0.249642 0.249642)
							(end 0.2794 0.1778)
						)
						(arc
							(start 0.2794 -0.1778)
							(mid 0.249642 -0.249642)
							(end 0.1778 -0.2794)
						)
					)
					(width 0)
					(fill yes)
				)
			)
		)
	)
	(footprint ""
		(layer "F.Cu")
		(at 79.801974 -149.2885)
		(property "Reference" "R596"
			(at 0 0 0)
			(layer "F.SilkS")
			(hide yes)
			(effects
				(font
					(size 1.27 1.27)
				)
			)
		)
		(property "Value" "4K7R2F-GP"
			(at 0.064008 -3.993896 0)
			(unlocked yes)
			(layer "F.Fab")
			(hide yes)
			(effects
				(font
					(size 1.016 1.016)
					(thickness 0.1524)
				)
			)
		)
		(property "Device Type" "R402H16"
			(at 0.064008 -5.517896 0)
			(unlocked yes)
			(layer "F.Fab")
			(hide yes)
			(effects
				(font
					(size 1.016 1.016)
					(thickness 0.1524)
				)
			)
		)
		(duplicate_pad_numbers_are_jumpers no)
		(fp_line
			(start -0.508 -0.9398)
			(end -0.508 0.9398)
			(stroke
				(width 0.1524)
				(type default)
			)
			(layer "F.SilkS")
		)
		(fp_line
			(start 0.508 -0.9398)
			(end -0.508 -0.9398)
			(stroke
				(width 0.1524)
				(type default)
			)
			(layer "F.SilkS")
		)
		(fp_rect
			(start -0.508 0.9398)
			(end 0.508 -0.9398)
			(stroke
				(width 0)
				(type default)
			)
			(fill no)
			(layer "F.CrtYd")
		)
		(fp_rect
			(start -0.508 0.9398)
			(end 0.508 -0.9398)
			(stroke
				(width 0)
				(type default)
			)
			(fill no)
			(layer "F.Fab")
		)
		(pad "1" smd custom
			(at 0 -0.4445)
			(size 0.1397 0.1397)
			(layers "F.Cu" "F.Mask" "F.Paste")
			(net "COMP_TO_BMC_RESET_R")
			(options
				(clearance outline)
				(anchor circle)
			)
			(primitives
				(gr_poly
					(pts
						(arc
							(start -0.1778 -0.2794)
							(mid -0.249642 -0.249642)
							(end -0.2794 -0.1778)
						)
						(arc
							(start -0.2794 0.1778)
							(mid -0.249642 0.249642)
							(end -0.1778 0.2794)
						)
						(arc
							(start 0.1778 0.2794)
							(mid 0.249642 0.249642)
							(end 0.2794 0.1778)
						)
						(arc
							(start 0.2794 -0.1778)
							(mid 0.249642 -0.249642)
							(end 0.1778 -0.2794)
						)
					)
					(width 0)
					(fill yes)
				)
			)
		)
		(pad "2" smd custom
			(at 0 0.4445)
			(size 0.1397 0.1397)
			(layers "F.Cu" "F.Mask" "F.Paste")
			(net "GND")
			(options
				(clearance outline)
				(anchor circle)
			)
			(primitives
				(gr_poly
					(pts
						(arc
							(start -0.1778 -0.2794)
							(mid -0.249642 -0.249642)
							(end -0.2794 -0.1778)
						)
						(arc
							(start -0.2794 0.1778)
							(mid -0.249642 0.249642)
							(end -0.1778 0.2794)
						)
						(arc
							(start 0.1778 0.2794)
							(mid 0.249642 0.249642)
							(end 0.2794 0.1778)
						)
						(arc
							(start 0.2794 -0.1778)
							(mid 0.249642 -0.249642)
							(end 0.1778 -0.2794)
						)
					)
					(width 0)
					(fill yes)
				)
			)
		)
	)
)
